(kicad_pcb
	(version 20260206)
	(generator "pcbnew")
	(generator_version "10.0")
	(general
		(thickness 1.6)
		(legacy_teardrops no)
	)
	(paper "A4")
	(title_block
		(title "peb — Lightning_PEB_BRD.brd")
		(comment 1 "Lightning (Wiwynn / Facebook NVMe JBOF) / footprints 114-119 of 2563")
	)
	(layers
		(0 "F.Cu" signal "TOP")
		(4 "In1.Cu" signal "L2GND")
		(6 "In2.Cu" signal "L3")
		(8 "In3.Cu" signal "L4VCC")
		(10 "In4.Cu" signal "L5VCC")
		(12 "In5.Cu" signal "L6")
		(14 "In6.Cu" signal "L7GND")
		(2 "B.Cu" signal "BOTTOM")
		(9 "F.Adhes" user "F.Adhesive")
		(11 "B.Adhes" user "B.Adhesive")
		(13 "F.Paste" user "Package Geometry/Pastemask Top")
		(15 "B.Paste" user "Package Geometry/Pastemask Bottom")
		(5 "F.SilkS" user "Ref Des/Silkscreen Top")
		(7 "B.SilkS" user "Ref Des/Silkscreen Bottom")
		(1 "F.Mask" user "Board Geometry/Soldermask Top")
		(3 "B.Mask" user "Board Geometry/Soldermask Bottom")
		(17 "Dwgs.User" user "User.Drawings")
		(19 "Cmts.User" user "User.Comments")
		(21 "Eco1.User" user "User.Eco1")
		(23 "Eco2.User" user "User.Eco2")
		(25 "Edge.Cuts" user "Board Geometry/Outline")
		(27 "Margin" user)
		(31 "F.CrtYd" user "Package Geometry/Place Bound Top")
		(29 "B.CrtYd" user "Package Geometry/Place Bound Bottom")
		(35 "F.Fab" user "Ref Des/Assembly Top")
		(33 "B.Fab" user "Ref Des/Assembly Bottom")
	)
	(footprint ""
		(layer "F.Cu")
		(at 71.940166 -85.37956 -90)
		(property "Reference" "U41"
			(at 0 0 270)
			(layer "F.SilkS")
			(hide yes)
			(effects
				(font
					(size 1.27 1.27)
				)
			)
		)
		(property "Value" "LM393ADR-1-GP"
			(at -3.707384 -1.5367 270)
			(unlocked yes)
			(layer "F.Fab")
			(hide yes)
			(effects
				(font
					(size 1.016 1.016)
					(thickness 0.1524)
				)
			)
		)
		(property "Device Type" "SOIC8H69"
			(at -3.707384 -3.0607 270)
			(unlocked yes)
			(layer "F.Fab")
			(hide yes)
			(effects
				(font
					(size 1.016 1.016)
					(thickness 0.1524)
				)
			)
		)
		(duplicate_pad_numbers_are_jumpers no)
		(fp_line
			(start -2.6289 3.4417)
			(end -2.6289 1.4732)
			(stroke
				(width 0.381)
				(type default)
			)
			(layer "F.SilkS")
		)
		(fp_line
			(start -2.7432 1.4224)
			(end -2.6416 1.4224)
			(stroke
				(width 0.1524)
				(type default)
			)
			(layer "F.SilkS")
		)
		(fp_line
			(start -2.7432 1.4224)
			(end 2.1336 1.4224)
			(stroke
				(width 0.1524)
				(type default)
			)
			(layer "F.SilkS")
		)
		(fp_line
			(start 2.1336 1.4224)
			(end 2.1336 -1.4224)
			(stroke
				(width 0.1524)
				(type default)
			)
			(layer "F.SilkS")
		)
		(fp_line
			(start -2.1844 -0.0508)
			(end -2.7178 0.508)
			(stroke
				(width 0.1524)
				(type default)
			)
			(layer "F.SilkS")
		)
		(fp_line
			(start -2.7178 -0.508)
			(end -2.1844 -0.0508)
			(stroke
				(width 0.1524)
				(type default)
			)
			(layer "F.SilkS")
		)
		(fp_line
			(start -2.7432 -1.4224)
			(end -2.7432 1.4224)
			(stroke
				(width 0.1524)
				(type default)
			)
			(layer "F.SilkS")
		)
		(fp_line
			(start 2.1336 -1.4224)
			(end -2.7432 -1.4224)
			(stroke
				(width 0.1524)
				(type default)
			)
			(layer "F.SilkS")
		)
		(fp_poly
			(pts
				(xy -2.2098 -1.4224) (xy -2.2098 1.4224) (xy 2.2098 1.4224) (xy 2.2098 -1.4224)
			)
			(stroke
				(width 0)
				(type default)
			)
			(fill yes)
			(layer "F.SilkS")
		)
		(fp_rect
			(start -2.450084 2.999994)
			(end 2.450084 -2.999994)
			(stroke
				(width 0)
				(type default)
			)
			(fill no)
			(layer "F.CrtYd")
		)
		(fp_poly
			(pts
				(xy -2.8194 3.6322) (xy -2.8194 -3.6322) (xy 2.8194 -3.6322) (xy 2.8194 1.18364) (xy 2.450084 1.18364)
				(xy 2.450084 -2.999994) (xy -2.450084 -2.999994) (xy -2.450084 2.999994) (xy 2.450084 2.999994)
				(xy 2.450084 1.18618) (xy 2.8194 1.18618) (xy 2.8194 3.6322)
			)
			(stroke
				(width 0)
				(type default)
			)
			(fill no)
			(layer "F.CrtYd")
		)
		(fp_rect
			(start -2.8194 3.6322)
			(end 2.8194 -3.6322)
			(stroke
				(width 0)
				(type default)
			)
			(fill no)
			(layer "F.Fab")
		)
		(pad "1" smd rect
			(at -1.905 2.54 270)
			(size 0.635 1.651)
			(layers "F.Cu" "F.Mask" "F.Paste")
			(net "HB_A_OUT")
		)
		(pad "2" smd rect
			(at -0.635 2.54 270)
			(size 0.635 1.651)
			(layers "F.Cu" "F.Mask" "F.Paste")
			(net "HB_A_IN")
		)
		(pad "3" smd rect
			(at 0.635 2.54 270)
			(size 0.635 1.651)
			(layers "F.Cu" "F.Mask" "F.Paste")
			(net "DIVIDER_1_IN")
		)
		(pad "4" smd rect
			(at 1.905 2.54 270)
			(size 0.635 1.651)
			(layers "F.Cu" "F.Mask" "F.Paste")
			(net "GND")
		)
		(pad "5" smd rect
			(at 1.905 -2.54 270)
			(size 0.635 1.651)
			(layers "F.Cu" "F.Mask" "F.Paste")
			(net "HB_A_IN")
		)
		(pad "6" smd rect
			(at 0.635 -2.54 270)
			(size 0.635 1.651)
			(layers "F.Cu" "F.Mask" "F.Paste")
			(net "DIVIDER_2_IN")
		)
		(pad "7" smd rect
			(at -0.635 -2.54 270)
			(size 0.635 1.651)
			(layers "F.Cu" "F.Mask" "F.Paste")
			(net "HB_A_OUT")
		)
		(pad "8" smd rect
			(at -1.905 -2.54 270)
			(size 0.635 1.651)
			(layers "F.Cu" "F.Mask" "F.Paste")
			(net "P3V3_STBY")
		)
	)
	(footprint ""
		(layer "F.Cu")
		(at 305.816 -68.834 180)
		(property "Reference" "C459"
			(at 0 0 180)
			(layer "F.SilkS")
			(hide yes)
			(effects
				(font
					(size 1.27 1.27)
				)
			)
		)
		(property "Value" "SC100U4V5MX-1-GP"
			(at -0.0762 -6.1214 180)
			(unlocked yes)
			(layer "F.Fab")
			(hide yes)
			(effects
				(font
					(size 1.016 1.016)
					(thickness 0.1524)
				)
			)
		)
		(property "Device Type" "C805H58"
			(at -0.0762 -8.1534 180)
			(unlocked yes)
			(layer "F.Fab")
			(hide yes)
			(effects
				(font
					(size 1.016 1.016)
					(thickness 0.1524)
				)
			)
		)
		(duplicate_pad_numbers_are_jumpers no)
		(fp_line
			(start 0.635 0)
			(end -0.635 0)
			(stroke
				(width 0.508)
				(type default)
			)
			(layer "F.SilkS")
		)
		(fp_rect
			(start -0.9652 1.778)
			(end 0.9652 -1.778)
			(stroke
				(width 0)
				(type default)
			)
			(fill no)
			(layer "F.CrtYd")
		)
		(fp_poly
			(pts
				(xy -0.9652 -1.778) (xy 0.9652 -1.778) (xy 0.9652 1.778) (xy -0.9652 1.778)
			)
			(stroke
				(width 0)
				(type default)
			)
			(fill no)
			(layer "F.Fab")
		)
		(pad "1" smd rect
			(at 0 -0.9652 180)
			(size 1.397 1.143)
			(layers "F.Cu" "F.Mask" "F.Paste")
			(net "DUT_VDD")
		)
		(pad "2" smd rect
			(at 0 0.9652 180)
			(size 1.397 1.143)
			(layers "F.Cu" "F.Mask" "F.Paste")
			(net "GND")
		)
	)
	(footprint ""
		(layer "F.Cu")
		(at 19.177 -148.844 -90)
		(property "Reference" "R333"
			(at 0 0 270)
			(layer "F.SilkS")
			(hide yes)
			(effects
				(font
					(size 1.27 1.27)
				)
			)
		)
		(property "Value" "47KR2F-GP"
			(at 0.064008 -3.993896 270)
			(unlocked yes)
			(layer "F.Fab")
			(hide yes)
			(effects
				(font
					(size 1.016 1.016)
					(thickness 0.1524)
				)
			)
		)
		(property "Device Type" "R402H16"
			(at 0.064008 -5.517896 270)
			(unlocked yes)
			(layer "F.Fab")
			(hide yes)
			(effects
				(font
					(size 1.016 1.016)
					(thickness 0.1524)
				)
			)
		)
		(duplicate_pad_numbers_are_jumpers no)
		(fp_line
			(start -0.508 -0.9398)
			(end -0.508 0.9398)
			(stroke
				(width 0.1524)
				(type default)
			)
			(layer "F.SilkS")
		)
		(fp_line
			(start 0.508 -0.9398)
			(end -0.508 -0.9398)
			(stroke
				(width 0.1524)
				(type default)
			)
			(layer "F.SilkS")
		)
		(fp_rect
			(start -0.508 0.9398)
			(end 0.508 -0.9398)
			(stroke
				(width 0)
				(type default)
			)
			(fill no)
			(layer "F.CrtYd")
		)
		(fp_rect
			(start -0.508 0.9398)
			(end 0.508 -0.9398)
			(stroke
				(width 0)
				(type default)
			)
			(fill no)
			(layer "F.Fab")
		)
		(pad "1" smd custom
			(at 0 -0.4445 270)
			(size 0.1397 0.1397)
			(layers "F.Cu" "F.Mask" "F.Paste")
			(net "P3V3_STBY")
			(options
				(clearance outline)
				(anchor circle)
			)
			(primitives
				(gr_poly
					(pts
						(arc
							(start -0.1778 -0.2794)
							(mid -0.249642 -0.249642)
							(end -0.2794 -0.1778)
						)
						(arc
							(start -0.2794 0.1778)
							(mid -0.249642 0.249642)
							(end -0.1778 0.2794)
						)
						(arc
							(start 0.1778 0.2794)
							(mid 0.249642 0.249642)
							(end 0.2794 0.1778)
						)
						(arc
							(start 0.2794 -0.1778)
							(mid 0.249642 -0.249642)
							(end 0.1778 -0.2794)
						)
					)
					(width 0)
					(fill yes)
				)
			)
		)
		(pad "2" smd custom
			(at 0 0.4445 270)
			(size 0.1397 0.1397)
			(layers "F.Cu" "F.Mask" "F.Paste")
			(net "FM_BMC_RESET_N")
			(options
				(clearance outline)
				(anchor circle)
			)
			(primitives
				(gr_poly
					(pts
						(arc
							(start -0.1778 -0.2794)
							(mid -0.249642 -0.249642)
							(end -0.2794 -0.1778)
						)
						(arc
							(start -0.2794 0.1778)
							(mid -0.249642 0.249642)
							(end -0.1778 0.2794)
						)
						(arc
							(start 0.1778 0.2794)
							(mid 0.249642 0.249642)
							(end 0.2794 0.1778)
						)
						(arc
							(start 0.2794 -0.1778)
							(mid 0.249642 -0.249642)
							(end 0.1778 -0.2794)
						)
					)
					(width 0)
					(fill yes)
				)
			)
		)
	)
	(footprint ""
		(layer "F.Cu")
		(at 118.17858 -33.929828 180)
		(property "Reference" "Q24"
			(at 0 0 180)
			(layer "F.SilkS")
			(hide yes)
			(effects
				(font
					(size 1.27 1.27)
				)
			)
		)
		(property "Value" "2N7002K-1-GP"
			(at 0.127 -8.9662 180)
			(unlocked yes)
			(layer "F.Fab")
			(hide yes)
			(effects
				(font
					(size 1.016 1.016)
					(thickness 0.1524)
				)
			)
		)
		(property "Device Type" "SOT23DGS2D4H44"
			(at 0.127 -10.4902 180)
			(unlocked yes)
			(layer "F.Fab")
			(hide yes)
			(effects
				(font
					(size 1.016 1.016)
					(thickness 0.1524)
				)
			)
		)
		(duplicate_pad_numbers_are_jumpers no)
		(fp_line
			(start 1.651 1.778)
			(end 1.651 -1.778)
			(stroke
				(width 0.1524)
				(type default)
			)
			(layer "F.SilkS")
		)
		(fp_line
			(start 1.651 -1.778)
			(end -1.651 -1.778)
			(stroke
				(width 0.1524)
				(type default)
			)
			(layer "F.SilkS")
		)
		(fp_line
			(start -1.651 1.778)
			(end 1.651 1.778)
			(stroke
				(width 0.1524)
				(type default)
			)
			(layer "F.SilkS")
		)
		(fp_line
			(start -1.651 -1.778)
			(end -1.651 1.778)
			(stroke
				(width 0.1524)
				(type default)
			)
			(layer "F.SilkS")
		)
		(fp_poly
			(pts
				(xy -1.778 1.8796) (xy -1.778 -1.8796) (xy 1.778 -1.8796) (xy 1.778 1.8796)
			)
			(stroke
				(width 0)
				(type default)
			)
			(fill no)
			(layer "F.CrtYd")
		)
		(fp_poly
			(pts
				(xy -1.778 1.8796) (xy -1.778 -1.8796) (xy 1.778 -1.8796) (xy 1.778 1.8796)
			)
			(stroke
				(width 0)
				(type default)
			)
			(fill no)
			(layer "F.Fab")
		)
		(pad "D" smd custom
			(at 0 -0.9525 180)
			(size 0.1905 0.1905)
			(layers "F.Cu" "F.Mask" "F.Paste")
			(net "LED_Q_1")
			(options
				(clearance outline)
				(anchor circle)
			)
			(primitives
				(gr_poly
					(pts
						(arc
							(start -0.1778 0.5715)
							(mid -0.321484 0.511984)
							(end -0.381 0.3683)
						)
						(arc
							(start -0.381 -0.3683)
							(mid -0.321484 -0.511984)
							(end -0.1778 -0.5715)
						)
						(arc
							(start 0.1778 -0.5715)
							(mid 0.321484 -0.511984)
							(end 0.381 -0.3683)
						)
						(arc
							(start 0.381 0.3683)
							(mid 0.321484 0.511984)
							(end 0.1778 0.5715)
						)
					)
					(width 0)
					(fill yes)
				)
			)
		)
		(pad "G" smd custom
			(at -0.98425 0.9525 180)
			(size 0.1905 0.1905)
			(layers "F.Cu" "F.Mask" "F.Paste")
			(net "UPLINK1_R")
			(options
				(clearance outline)
				(anchor circle)
			)
			(primitives
				(gr_poly
					(pts
						(arc
							(start -0.1778 0.5715)
							(mid -0.321484 0.511984)
							(end -0.381 0.3683)
						)
						(arc
							(start -0.381 -0.3683)
							(mid -0.321484 -0.511984)
							(end -0.1778 -0.5715)
						)
						(arc
							(start 0.1778 -0.5715)
							(mid 0.321484 -0.511984)
							(end 0.381 -0.3683)
						)
						(arc
							(start 0.381 0.3683)
							(mid 0.321484 0.511984)
							(end 0.1778 0.5715)
						)
					)
					(width 0)
					(fill yes)
				)
			)
		)
		(pad "S" smd custom
			(at 0.98425 0.9525 180)
			(size 0.1905 0.1905)
			(layers "F.Cu" "F.Mask" "F.Paste")
			(net "GND")
			(options
				(clearance outline)
				(anchor circle)
			)
			(primitives
				(gr_poly
					(pts
						(arc
							(start -0.1778 0.5715)
							(mid -0.321484 0.511984)
							(end -0.381 0.3683)
						)
						(arc
							(start -0.381 -0.3683)
							(mid -0.321484 -0.511984)
							(end -0.1778 -0.5715)
						)
						(arc
							(start 0.1778 -0.5715)
							(mid 0.321484 -0.511984)
							(end 0.381 -0.3683)
						)
						(arc
							(start 0.381 0.3683)
							(mid 0.321484 0.511984)
							(end 0.1778 0.5715)
						)
					)
					(width 0)
					(fill yes)
				)
			)
		)
	)
	(footprint ""
		(layer "F.Cu")
		(at 43.9928 -191.3636 -90)
		(property "Reference" "R873"
			(at 0 0 270)
			(layer "F.SilkS")
			(hide yes)
			(effects
				(font
					(size 1.27 1.27)
				)
			)
		)
		(property "Value" "2KR2F-3-GP"
			(at 0.064008 -3.993896 270)
			(unlocked yes)
			(layer "F.Fab")
			(hide yes)
			(effects
				(font
					(size 1.016 1.016)
					(thickness 0.1524)
				)
			)
		)
		(property "Device Type" "R402H16"
			(at 0.064008 -5.517896 270)
			(unlocked yes)
			(layer "F.Fab")
			(hide yes)
			(effects
				(font
					(size 1.016 1.016)
					(thickness 0.1524)
				)
			)
		)
		(duplicate_pad_numbers_are_jumpers no)
		(fp_line
			(start -0.508 -0.9398)
			(end -0.508 0.9398)
			(stroke
				(width 0.1524)
				(type default)
			)
			(layer "F.SilkS")
		)
		(fp_line
			(start 0.508 -0.9398)
			(end -0.508 -0.9398)
			(stroke
				(width 0.1524)
				(type default)
			)
			(layer "F.SilkS")
		)
		(fp_rect
			(start -0.508 0.9398)
			(end 0.508 -0.9398)
			(stroke
				(width 0)
				(type default)
			)
			(fill no)
			(layer "F.CrtYd")
		)
		(fp_rect
			(start -0.508 0.9398)
			(end 0.508 -0.9398)
			(stroke
				(width 0)
				(type default)
			)
			(fill no)
			(layer "F.Fab")
		)
		(pad "1" smd custom
			(at 0 -0.4445 270)
			(size 0.1397 0.1397)
			(layers "F.Cu" "F.Mask" "F.Paste")
			(net "P3V3_STBY")
			(options
				(clearance outline)
				(anchor circle)
			)
			(primitives
				(gr_poly
					(pts
						(arc
							(start -0.1778 -0.2794)
							(mid -0.249642 -0.249642)
							(end -0.2794 -0.1778)
						)
						(arc
							(start -0.2794 0.1778)
							(mid -0.249642 0.249642)
							(end -0.1778 0.2794)
						)
						(arc
							(start 0.1778 0.2794)
							(mid 0.249642 0.249642)
							(end 0.2794 0.1778)
						)
						(arc
							(start 0.2794 -0.1778)
							(mid 0.249642 -0.249642)
							(end 0.1778 -0.2794)
						)
					)
					(width 0)
					(fill yes)
				)
			)
		)
		(pad "2" smd custom
			(at 0 0.4445 270)
			(size 0.1397 0.1397)
			(layers "F.Cu" "F.Mask" "F.Paste")
			(net "BUF_I2C9_CLKBUF2_SCL_R")
			(options
				(clearance outline)
				(anchor circle)
			)
			(primitives
				(gr_poly
					(pts
						(arc
							(start -0.1778 -0.2794)
							(mid -0.249642 -0.249642)
							(end -0.2794 -0.1778)
						)
						(arc
							(start -0.2794 0.1778)
							(mid -0.249642 0.249642)
							(end -0.1778 0.2794)
						)
						(arc
							(start 0.1778 0.2794)
							(mid 0.249642 0.249642)
							(end 0.2794 0.1778)
						)
						(arc
							(start 0.2794 -0.1778)
							(mid 0.249642 -0.249642)
							(end 0.1778 -0.2794)
						)
					)
					(width 0)
					(fill yes)
				)
			)
		)
	)
	(footprint ""
		(layer "F.Cu")
		(at 64.4906 -109.3724 90)
		(property "Reference" "U28"
			(at 0 0 90)
			(layer "F.SilkS")
			(hide yes)
			(effects
				(font
					(size 1.27 1.27)
				)
			)
		)
		(property "Value" "2N7002DW-7F-GP"
			(at -2.3622 -8.2042 90)
			(unlocked yes)
			(layer "F.Fab")
			(hide yes)
			(effects
				(font
					(size 1.016 1.016)
					(thickness 0.1524)
				)
			)
		)
		(property "Device Type" "SOT-363H44"
			(at -2.3622 -10.1092 90)
			(unlocked yes)
			(layer "F.Fab")
			(hide yes)
			(effects
				(font
					(size 1.016 1.016)
					(thickness 0.1524)
				)
			)
		)
		(duplicate_pad_numbers_are_jumpers no)
		(fp_line
			(start 1.4478 -1.7018)
			(end -1.4478 -1.7018)
			(stroke
				(width 0.1524)
				(type default)
			)
			(layer "F.SilkS")
		)
		(fp_line
			(start -1.4478 -1.7018)
			(end -1.4478 1.7018)
			(stroke
				(width 0.1524)
				(type default)
			)
			(layer "F.SilkS")
		)
		(fp_line
			(start -1.27 1.524)
			(end -1.27 0.6604)
			(stroke
				(width 0.4826)
				(type default)
			)
			(layer "F.SilkS")
		)
		(fp_line
			(start 1.4478 1.7018)
			(end 1.4478 -1.7018)
			(stroke
				(width 0.1524)
				(type default)
			)
			(layer "F.SilkS")
		)
		(fp_line
			(start -1.4478 1.7018)
			(end 1.4478 1.7018)
			(stroke
				(width 0.1524)
				(type default)
			)
			(layer "F.SilkS")
		)
		(fp_poly
			(pts
				(xy -1.524 -1.778) (xy 1.524 -1.778) (xy 1.524 1.778) (xy -1.524 1.778)
			)
			(stroke
				(width 0)
				(type default)
			)
			(fill no)
			(layer "F.CrtYd")
		)
		(fp_poly
			(pts
				(xy -1.524 -1.778) (xy 1.524 -1.778) (xy 1.524 1.778) (xy -1.524 1.778)
			)
			(stroke
				(width 0)
				(type default)
			)
			(fill no)
			(layer "F.Fab")
		)
		(pad "1" smd rect
			(at -0.65024 0.9398 90)
			(size 0.4064 1.016)
			(layers "F.Cu" "F.Mask" "F.Paste")
			(net "BMC_I2C11_MINI5_SCL_S")
		)
		(pad "2" smd rect
			(at 0 0.9398 90)
			(size 0.4064 1.016)
			(layers "F.Cu" "F.Mask" "F.Paste")
			(net "I2C5_LS_G2")
		)
		(pad "3" smd rect
			(at 0.65024 0.9398 90)
			(size 0.4064 1.016)
			(layers "F.Cu" "F.Mask" "F.Paste")
			(net "BMC_I2C11_MINI5_SDA")
		)
		(pad "4" smd rect
			(at 0.65024 -0.9398 90)
			(size 0.4064 1.016)
			(layers "F.Cu" "F.Mask" "F.Paste")
			(net "BMC_I2C11_MINI5_SDA_S")
		)
		(pad "5" smd rect
			(at 0 -0.9398 90)
			(size 0.4064 1.016)
			(layers "F.Cu" "F.Mask" "F.Paste")
			(net "I2C5_LS_G1")
		)
		(pad "6" smd rect
			(at -0.65024 -0.9398 90)
			(size 0.4064 1.016)
			(layers "F.Cu" "F.Mask" "F.Paste")
			(net "BMC_I2C11_MINI5_SCL")
		)
	)
)
